# T6G (Grand Teton) — schematic netlist excerpt (pin names and nets, part order shuffled) for the footprints in the layout excerpt that follows; sources: Cadence DE-HDL packaged netlist, KiCad conversion of 04192023_DAF0TMB3IC0_F0TG_MB_C_brd_V02_OCP.brd

PC316_5  Q_CAP  22UF 4V 20% X6S  pkg C0805  page 213 : A = PVDDCR_CPU0_P1 ; B = GND
R4507  Q_RES  33.2 1% CHIP  pkg 0402LF  page 150 : A = SMB_CPU0_CPU1_SEC_SDA ; B = SMB_CPU0_CPU1_SEC_SDA_R
R3439  Q_RES  100K 1% CHIP  pkg 0402LF  page 126 : A = P3V3_AUX ; B = GPU_FPGA_THERM_OVERT_ISO_N

(kicad_pcb
	(version 20260206)
	(generator "pcbnew")
	(generator_version "10.0")
	(general
		(thickness 1.6)
		(legacy_teardrops no)
	)
	(paper "A4")
	(title_block
		(title "04192023_DAF0TMB3IC0_F0TG_MB_C_brd_V02_OCP.brd")
		(comment 1 "Grand Teton / footprints 5831-5833 of 8354")
	)
	(layers
		(0 "F.Cu" signal "TOP")
		(4 "In1.Cu" signal "GND")
		(6 "In2.Cu" signal "IN1")
		(8 "In3.Cu" signal "GND1")
		(10 "In4.Cu" signal "IN2")
		(12 "In5.Cu" signal "GND2")
		(14 "In6.Cu" signal "IN3")
		(16 "In7.Cu" signal "GND3")
		(18 "In8.Cu" signal "VCC")
		(20 "In9.Cu" signal "VCC1")
		(22 "In10.Cu" signal "GND4")
		(24 "In11.Cu" signal "IN4")
		(26 "In12.Cu" signal "GND5")
		(28 "In13.Cu" signal "IN5")
		(30 "In14.Cu" signal "GND6")
		(32 "In15.Cu" signal "IN6")
		(34 "In16.Cu" signal "GND7")
		(2 "B.Cu" signal "BOTTOM")
		(9 "F.Adhes" user "F.Adhesive")
		(11 "B.Adhes" user "B.Adhesive")
		(13 "F.Paste" user "Package Geometry/Pastemask Top")
		(15 "B.Paste" user "Package Geometry/Pastemask Bottom")
		(5 "F.SilkS" user "Ref Des/Silkscreen Top")
		(7 "B.SilkS" user "Ref Des/Silkscreen Bottom")
		(1 "F.Mask" user "Board Geometry/Soldermask Top")
		(3 "B.Mask" user "Board Geometry/Soldermask Bottom")
		(17 "Dwgs.User" user "User.Drawings")
		(19 "Cmts.User" user "User.Comments")
		(21 "Eco1.User" user "User.Eco1")
		(23 "Eco2.User" user "User.Eco2")
		(25 "Edge.Cuts" user "Board Geometry/Outline")
		(27 "Margin" user)
		(31 "F.CrtYd" user "Package Geometry/Place Bound Top")
		(29 "B.CrtYd" user "Package Geometry/Place Bound Bottom")
		(35 "F.Fab" user "Ref Des/Assembly Top")
		(33 "B.Fab" user "Ref Des/Assembly Bottom")
	)
	(footprint ""
		(layer "B.Cu")
		(at 52.782978 -431.904902 -90)
		(property "Reference" "R3439"
			(at 0 0 90)
			(layer "B.SilkS")
			(hide yes)
			(effects
				(font
					(size 1.27 1.27)
				)
				(justify mirror)
			)
		)
		(property "Value" ""
			(at 0 0 90)
			(layer "B.Fab")
			(effects
				(font
					(size 1.27 1.27)
				)
				(justify mirror)
			)
		)
		(duplicate_pad_numbers_are_jumpers no)
		(fp_line
			(start -0.7874 0.4064)
			(end 0.7874 0.4064)
			(stroke
				(width 0.1524)
				(type default)
			)
			(layer "B.SilkS")
		)
		(fp_line
			(start 0.7874 0.4064)
			(end 0.7874 -0.4064)
			(stroke
				(width 0.1524)
				(type default)
			)
			(layer "B.SilkS")
		)
		(fp_line
			(start -0.7874 -0.4064)
			(end -0.7874 0.4064)
			(stroke
				(width 0.1524)
				(type default)
			)
			(layer "B.SilkS")
		)
		(fp_line
			(start 0.7874 -0.4064)
			(end -0.7874 -0.4064)
			(stroke
				(width 0.1524)
				(type default)
			)
			(layer "B.SilkS")
		)
		(fp_line
			(start -0.67945 0.3048)
			(end -0.120396 0.3048)
			(stroke
				(width 0.1)
				(type default)
			)
			(layer "B.Fab")
		)
		(fp_line
			(start -0.120396 0.3048)
			(end -0.120396 0.2794)
			(stroke
				(width 0.1)
				(type default)
			)
			(layer "B.Fab")
		)
		(fp_line
			(start 0.12065 0.3048)
			(end 0.67945 0.3048)
			(stroke
				(width 0.1)
				(type default)
			)
			(layer "B.Fab")
		)
		(fp_line
			(start 0.67945 0.3048)
			(end 0.67945 -0.305054)
			(stroke
				(width 0.1)
				(type default)
			)
			(layer "B.Fab")
		)
		(fp_line
			(start -0.120396 0.2794)
			(end 0.12065 0.2794)
			(stroke
				(width 0.1)
				(type default)
			)
			(layer "B.Fab")
		)
		(fp_line
			(start 0.12065 0.2794)
			(end 0.12065 0.3048)
			(stroke
				(width 0.1)
				(type default)
			)
			(layer "B.Fab")
		)
		(fp_line
			(start -0.12065 -0.2794)
			(end -0.12065 -0.3048)
			(stroke
				(width 0.1)
				(type default)
			)
			(layer "B.Fab")
		)
		(fp_line
			(start 0.12065 -0.2794)
			(end -0.12065 -0.2794)
			(stroke
				(width 0.1)
				(type default)
			)
			(layer "B.Fab")
		)
		(fp_line
			(start -0.67945 -0.3048)
			(end -0.67945 0.3048)
			(stroke
				(width 0.1)
				(type default)
			)
			(layer "B.Fab")
		)
		(fp_line
			(start -0.12065 -0.3048)
			(end -0.67945 -0.3048)
			(stroke
				(width 0.1)
				(type default)
			)
			(layer "B.Fab")
		)
		(fp_line
			(start 0.12065 -0.305054)
			(end 0.12065 -0.2794)
			(stroke
				(width 0.1)
				(type default)
			)
			(layer "B.Fab")
		)
		(fp_line
			(start 0.67945 -0.305054)
			(end 0.12065 -0.305054)
			(stroke
				(width 0.1)
				(type default)
			)
			(layer "B.Fab")
		)
		(pad "1" smd circle
			(at 0.40005 0 90)
			(size 0 0)
			(layers "B.Cu" "B.Mask" "B.Paste")
			(net "P3V3_AUX")
		)
		(pad "2" smd circle
			(at -0.40005 0 90)
			(size 0 0)
			(layers "B.Cu" "B.Mask" "B.Paste")
			(net "GPU_FPGA_THERM_OVERT_ISO_N")
		)
	)
	(footprint ""
		(layer "B.Cu")
		(at 176.3776 -13.762228 90)
		(property "Reference" "R4507"
			(at 0 0 90)
			(layer "B.SilkS")
			(hide yes)
			(effects
				(font
					(size 1.27 1.27)
				)
				(justify mirror)
			)
		)
		(property "Value" ""
			(at 0 0 90)
			(layer "B.Fab")
			(effects
				(font
					(size 1.27 1.27)
				)
				(justify mirror)
			)
		)
		(duplicate_pad_numbers_are_jumpers no)
		(fp_line
			(start 0.7874 -0.4064)
			(end -0.7874 -0.4064)
			(stroke
				(width 0.1524)
				(type default)
			)
			(layer "B.SilkS")
		)
		(fp_line
			(start -0.7874 -0.4064)
			(end -0.7874 0.4064)
			(stroke
				(width 0.1524)
				(type default)
			)
			(layer "B.SilkS")
		)
		(fp_line
			(start 0.7874 0.4064)
			(end 0.7874 -0.4064)
			(stroke
				(width 0.1524)
				(type default)
			)
			(layer "B.SilkS")
		)
		(fp_line
			(start -0.7874 0.4064)
			(end 0.7874 0.4064)
			(stroke
				(width 0.1524)
				(type default)
			)
			(layer "B.SilkS")
		)
		(fp_line
			(start 0.67945 -0.305054)
			(end 0.12065 -0.305054)
			(stroke
				(width 0.1)
				(type default)
			)
			(layer "B.Fab")
		)
		(fp_line
			(start 0.12065 -0.305054)
			(end 0.12065 -0.2794)
			(stroke
				(width 0.1)
				(type default)
			)
			(layer "B.Fab")
		)
		(fp_line
			(start -0.12065 -0.3048)
			(end -0.67945 -0.3048)
			(stroke
				(width 0.1)
				(type default)
			)
			(layer "B.Fab")
		)
		(fp_line
			(start -0.67945 -0.3048)
			(end -0.67945 0.3048)
			(stroke
				(width 0.1)
				(type default)
			)
			(layer "B.Fab")
		)
		(fp_line
			(start 0.12065 -0.2794)
			(end -0.12065 -0.2794)
			(stroke
				(width 0.1)
				(type default)
			)
			(layer "B.Fab")
		)
		(fp_line
			(start -0.12065 -0.2794)
			(end -0.12065 -0.3048)
			(stroke
				(width 0.1)
				(type default)
			)
			(layer "B.Fab")
		)
		(fp_line
			(start 0.12065 0.2794)
			(end 0.12065 0.3048)
			(stroke
				(width 0.1)
				(type default)
			)
			(layer "B.Fab")
		)
		(fp_line
			(start -0.120396 0.2794)
			(end 0.12065 0.2794)
			(stroke
				(width 0.1)
				(type default)
			)
			(layer "B.Fab")
		)
		(fp_line
			(start 0.67945 0.3048)
			(end 0.67945 -0.305054)
			(stroke
				(width 0.1)
				(type default)
			)
			(layer "B.Fab")
		)
		(fp_line
			(start 0.12065 0.3048)
			(end 0.67945 0.3048)
			(stroke
				(width 0.1)
				(type default)
			)
			(layer "B.Fab")
		)
		(fp_line
			(start -0.120396 0.3048)
			(end -0.120396 0.2794)
			(stroke
				(width 0.1)
				(type default)
			)
			(layer "B.Fab")
		)
		(fp_line
			(start -0.67945 0.3048)
			(end -0.120396 0.3048)
			(stroke
				(width 0.1)
				(type default)
			)
			(layer "B.Fab")
		)
		(pad "1" smd circle
			(at 0.40005 0 270)
			(size 0 0)
			(layers "B.Cu" "B.Mask" "B.Paste")
			(net "SMB_CPU0_CPU1_SEC_SDA")
		)
		(pad "2" smd circle
			(at -0.40005 0 270)
			(size 0 0)
			(layers "B.Cu" "B.Mask" "B.Paste")
			(net "SMB_CPU0_CPU1_SEC_SDA_R")
		)
	)
	(footprint ""
		(layer "B.Cu")
		(at 63.385954 -177.349912 90)
		(property "Reference" "PC316_5"
			(at 0 0 90)
			(layer "B.SilkS")
			(hide yes)
			(effects
				(font
					(size 1.27 1.27)
				)
				(justify mirror)
			)
		)
		(property "Value" ""
			(at 0 0 90)
			(layer "B.Fab")
			(effects
				(font
					(size 1.27 1.27)
				)
				(justify mirror)
			)
		)
		(duplicate_pad_numbers_are_jumpers no)
		(fp_line
			(start 1.524 -0.762)
			(end -1.524 -0.762)
			(stroke
				(width 0.1524)
				(type default)
			)
			(layer "B.SilkS")
		)
		(fp_line
			(start -1.524 -0.762)
			(end -1.524 0.762)
			(stroke
				(width 0.1524)
				(type default)
			)
			(layer "B.SilkS")
		)
		(fp_line
			(start 1.524 0.762)
			(end 1.524 -0.762)
			(stroke
				(width 0.1524)
				(type default)
			)
			(layer "B.SilkS")
		)
		(fp_line
			(start -1.524 0.762)
			(end 1.524 0.762)
			(stroke
				(width 0.1524)
				(type default)
			)
			(layer "B.SilkS")
		)
		(fp_line
			(start 1.1049 -0.724916)
			(end 1.1049 0.724916)
			(stroke
				(width 0.1)
				(type default)
			)
			(layer "B.Fab")
		)
		(fp_line
			(start -1.1049 -0.724916)
			(end 1.1049 -0.724916)
			(stroke
				(width 0.1)
				(type default)
			)
			(layer "B.Fab")
		)
		(fp_line
			(start 1.1049 0.724916)
			(end -1.1049 0.724916)
			(stroke
				(width 0.1)
				(type default)
			)
			(layer "B.Fab")
		)
		(fp_line
			(start -1.1049 0.724916)
			(end -1.1049 -0.724916)
			(stroke
				(width 0.1)
				(type default)
			)
			(layer "B.Fab")
		)
		(pad "1" smd rect
			(at 0.889 0 90)
			(size 1.016 1.27)
			(layers "B.Cu" "B.Mask" "B.Paste")
			(net "PVDDCR_CPU0_P1")
		)
		(pad "2" smd rect
			(at -0.889 0 90)
			(size 1.016 1.27)
			(layers "B.Cu" "B.Mask" "B.Paste")
			(net "GND")
		)
	)
)
